FILE_TYPE = MACRO_DRAWING;
SET COLOR_WIRE YELLOW;
SET COLOR_PROP ORANGE;
SET COLOR_DOT WHITE;
SET COLOR_ARC YELLOW;
SET COLOR_BODY GREEN;
SET COLOR_NOTE PURPLE;
SET PROP_DISPLAY VALUE;
SET PAGE_NUMBER P250;
FORCEADD QUANTA_TITLE_BLOCK_C..1
(1000 -4275);
FORCEPROP 1 LAST CUSTOM_TXT_CDS <NAME_2>
J 0
(-2175 -4225);
FORCEPROP 1 LAST CUSTOM_TXT_CDS <NAME_1>
J 0
(-2175 -4100);
FORCEPROP 1 LAST CUSTOM_TXT_CDS <Q_PROJ>
J 0
(-1382 -4173);
DISPLAY 1.212766 (-1382 -4173);
FORCEPROP 1 LAST CUSTOM_TXT_CDS <Q_REV>
J 0
(816 -4172);
DISPLAY 1.212766 (816 -4172);
FORCEPROP 1 LAST CUSTOM_TXT_CDS <CON_PAGE_NUM> OF <CON_TOTAL_PAGES>
J 0
(554 -4257);
DISPLAY 0.978723 (554 -4257);
FORCEPROP 1 LAST Q_TITLE BLANK
J 0
(-8316 -4249);
DISPLAY 2.446809 (-8316 -4249);
PAINT GREEN (-8316 -4249);
FORCEPROP 2 LAST CUSTOM_TXT_CDS <Q_NUMBER>
J 0
(-403 -4172);
DISPLAY 1.212766 (-403 -4172);
FORCEPROP 2 LAST CUSTOM_TXT_CDS <CON_LAST_MODIFIED>
J 0
(-885 -4260);
DISPLAY 0.978723 (-885 -4260);
FORCEPROP 1 LAST Q_DEPT 
J 1
(-2763 -4226);
DISPLAY 1.957447 (-2763 -4226);
PAINT GREEN (-2763 -4226);
FORCEPROP 2 LAST CDS_XR_PAGE_TITLE CR-264 : @S9S_MB_2U_LIB.S9S_MB_2U(SCH_1):PAGE264
J 0
(-6890 975);
DISPLAY 0.638298 (-6890 975);
PAINT PINK (-6890 975);
DISPLAY INVISIBLE (-6890 975);
FORCEPROP 2 LAST PAGE_BORDER TRUE
J 0
(-6890 975);
DISPLAY 0.638298 (-6890 975);
PAINT PINK (-6890 975);
DISPLAY INVISIBLE (-6890 975);
FORCEPROP 1 LAST CDS_LMAN_SYM_OUTLINE -9475,6775,100,-125
J 0
(1000 -4275);
DISPLAY 0.468085 (1000 -4275);
PAINT GREEN (1000 -4275);
DISPLAY INVISIBLE (1000 -4275);
FORCEPROP 2 LAST CDS_LIB pure_quanta
J 0
(1000 -4275);
DISPLAY INVISIBLE (1000 -4275);
FORCEPROP 1 LAST COMMENT_BODY TRUE
J 0
(1012 -4288);
DISPLAY 0.978723 (1012 -4288);
PAINT GREEN (1012 -4288);
DISPLAY INVISIBLE (1012 -4288);
FORCEPROP 2 LAST BOM_COST VR_PCH
J 0
(-2175 -4075);
DISPLAY 0.680851 (-2175 -4075);
DISPLAY INVISIBLE (-2175 -4075);
FORCEPROP 2 LAST CUSTOM_TXT_CDS <XR_PAGE_TITLE>
J 0
(-6890 975);
DISPLAY 0.638298 (-6890 975);
PAINT PINK (-6890 975);
DISPLAY INVISIBLE (-6890 975);
FORCEPROP 0 LAST CDS_CON_LAST_MODIFIED Thu Aug 24 16:16:22 2023
J 0
(-885 -4260);
DISPLAY INVISIBLE (-885 -4260);
FORCENOTE
THIS PAGE WAS INTENTIONALLY LEFT BLANK
(-7975 -1050) 0;
DISPLAY LEFT (-7975 -1050);
DISPLAY 4.914894 (-7975 -1050);
QUIT
